FILE_TYPE = CONNECTIVITY;
{Allegro Design Entry HDL 17.2-2016 S081 (4005846) 1/11/2022}
"PAGE_NUMBER" = 90;
0"NC";
1"M_F_CPU0_SA_CB<7:0>";
2"M_F_CPU0_SA_CA<6:0>";
3"M_F_CPU0_SB_CA<6:0>";
4"M_F_CPU0_SB_CB<7:0>";
5"M_F_CPU0_SA_DQ<31:0>";
6"M_F_CPU0_SB_DQ<31:0>";
7"M_F_CPU0_SA_DQS_DN<9:0>";
8"M_F_CPU0_SA_DQS_DP<9:0>";
9"M_F_CPU0_SB_DQS_DN<9:0>";
10"M_F_CPU0_SB_DQS_DP<9:0>";
11"GND\g";
12"GND\g";
13"P3V3_STBY\g";
14"I3C_SPD_DDRAF_CPU0_SDA";
15"I3C_SPD_DDRF_CPU0_SCL";
16"PWRGD_CHF_CPU0_DIMM";
17"I3C_SPD_DDRAF_CPU0_SCL";
18"P3V3_STBY\g";
19"PD_CHF_CPU0_DIMM_SAA";
20"TP_CHF_CPU0_DIMM_RFU_6";
21"GND\g";
22"P12V_MEM_1\g";
23"GND\g";
24"M_F_CPU0_SA_DQ<14>";
25"M_F_CPU0_SB_DQS_DP<9>";
26"M_F_CPU0_SB_DQS_DN<9>";
27"M_F_CPU0_SA_DQS_DP<9>";
28"M_F_CPU0_SA_DQS_DN<9>";
29"M_F_CPU0_SA_DQS_DP<8>";
30"M_F_CPU0_SA_DQS_DN<8>";
31"M_F_CPU0_SB_DQS_DN<7>";
32"M_F_CPU0_SA_DQS_DP<7>";
33"M_F_CPU0_SB_DQS_DP<6>";
34"M_F_CPU0_SB_DQS_DN<6>";
35"M_F_CPU0_SA_DQS_DN<6>";
36"M_F_CPU0_SB_DQS_DP<5>";
37"M_F_CPU0_SB_DQS_DN<5>";
38"M_F_CPU0_SA_DQS_DP<5>";
39"M_F_CPU0_SA_DQS_DN<5>";
40"M_F_CPU0_SB_DQS_DP<4>";
41"M_F_CPU0_SB_DQS_DN<4>";
42"M_F_CPU0_SA_DQS_DP<4>";
43"M_F_CPU0_SA_DQS_DN<4>";
44"M_F_CPU0_SB_DQS_DP<3>";
45"M_F_CPU0_SB_DQS_DN<3>";
46"M_F_CPU0_SA_DQS_DP<3>";
47"M_F_CPU0_SA_DQS_DN<3>";
48"M_F_CPU0_SB_DQS_DP<2>";
49"M_F_CPU0_SB_DQS_DN<2>";
50"M_F_CPU0_SA_DQS_DP<2>";
51"M_F_CPU0_SA_DQS_DN<2>";
52"M_F_CPU0_SB_DQS_DP<1>";
53"M_F_CPU0_SB_DQS_DN<1>";
54"M_F_CPU0_SA_DQS_DP<1>";
55"M_F_CPU0_SA_DQS_DN<1>";
56"M_F_CPU0_SB_DQS_DP<0>";
57"M_F_CPU0_SB_DQS_DN<0>";
58"M_F_CPU0_SA_DQS_DP<0>";
59"M_F_CPU0_SA_DQS_DN<0>";
60"M_F_CPU0_SB_DQS_DP<7>";
61"M_F_CPU0_SB_DQS_DN<8>";
62"M_F_CPU0_SB_DQS_DP<8>";
63"M_F_CPU0_SA_DQS_DP<6>";
64"M_F_CPU0_SA_DQS_DN<7>";
65"M_F_CPU0_SA_DQ<22>";
66"M_F_CPU0_SB_PAR";
67"M_F_CPU0_SA_PAR";
68"M_F_CPU0_SA_CA<5>";
69"M_F_CPU0_SA_CA<6>";
70"M_F_CPU0_SA_DQ<28>";
71"M_F_CPU0_SA_DQ<31>";
72"TP_CHF_CPU0_DIMM_RFU_0";
73"TP_CHF_CPU0_DIMM_RFU_1";
74"TP_CHF_CPU0_DIMM_RFU_2";
75"TP_CHF_CPU0_DIMM_RFU_3";
76"TP_CHF_CPU0_DIMM_RFU_4";
77"TP_CHF_CPU0_DIMM_RFU_5";
78"M_F_CPU0_RESET_N";
79"M_F_CPU0_SB_RSP<0>";
80"M_F_CPU0_SA_RSP<0>";
81"M_F_CPU0_SB_DQ<0>";
82"M_F_CPU0_SB_DQ<1>";
83"M_F_CPU0_SB_DQ<2>";
84"M_F_CPU0_SB_DQ<3>";
85"M_F_CPU0_SB_DQ<4>";
86"M_F_CPU0_SB_DQ<5>";
87"M_F_CPU0_SB_DQ<6>";
88"M_F_CPU0_SB_DQ<7>";
89"M_F_CPU0_SB_DQ<8>";
90"M_F_CPU0_SB_DQ<9>";
91"M_F_CPU0_SB_DQ<10>";
92"M_F_CPU0_SB_DQ<11>";
93"M_F_CPU0_SB_DQ<12>";
94"M_F_CPU0_SB_DQ<13>";
95"M_F_CPU0_SB_DQ<14>";
96"M_F_CPU0_SB_DQ<15>";
97"M_F_CPU0_SB_DQ<16>";
98"M_F_CPU0_SB_DQ<17>";
99"M_F_CPU0_SB_DQ<18>";
100"M_F_CPU0_SB_DQ<19>";
101"M_F_CPU0_SB_DQ<20>";
102"M_F_CPU0_SB_DQ<21>";
103"M_F_CPU0_SB_DQ<22>";
104"M_F_CPU0_SB_DQ<23>";
105"M_F_CPU0_SB_DQ<24>";
106"M_F_CPU0_SB_DQ<25>";
107"M_F_CPU0_SB_DQ<26>";
108"M_F_CPU0_SB_DQ<27>";
109"M_F_CPU0_SB_DQ<28>";
110"M_F_CPU0_SB_DQ<29>";
111"M_F_CPU0_SB_DQ<30>";
112"M_F_CPU0_SB_DQ<31>";
113"M_F_CPU0_SA_DQ<0>";
114"M_F_CPU0_SA_DQ<1>";
115"M_F_CPU0_SA_DQ<2>";
116"M_F_CPU0_SA_DQ<3>";
117"M_F_CPU0_SA_DQ<4>";
118"M_F_CPU0_SA_DQ<5>";
119"M_F_CPU0_SA_DQ<6>";
120"M_F_CPU0_SA_DQ<7>";
121"M_F_CPU0_SA_DQ<8>";
122"M_F_CPU0_SA_DQ<9>";
123"M_F_CPU0_SA_DQ<10>";
124"M_F_CPU0_SA_DQ<11>";
125"M_F_CPU0_SA_DQ<12>";
126"M_F_CPU0_SA_DQ<13>";
127"M_F_CPU0_SA_DQ<15>";
128"M_F_CPU0_SA_DQ<16>";
129"M_F_CPU0_SA_DQ<17>";
130"M_F_CPU0_SA_DQ<18>";
131"M_F_CPU0_SA_DQ<19>";
132"M_F_CPU0_SA_DQ<20>";
133"M_F_CPU0_SA_DQ<21>";
134"M_F_CPU0_SA_DQ<23>";
135"M_F_CPU0_SA_DQ<24>";
136"M_F_CPU0_SA_DQ<25>";
137"M_F_CPU0_SA_DQ<26>";
138"M_F_CPU0_SA_DQ<27>";
139"M_F_CPU0_SA_DQ<29>";
140"M_F_CPU0_SA_DQ<30>";
141"M_F_CPU0_SB_CS_N<1>";
142"M_F_CPU0_SA_CS_N<1>";
143"M_F_CPU0_SB_CS_N<0>";
144"M_F_CPU0_SA_CS_N<0>";
145"M_F_CPU0_CLK_DP<0>";
146"M_F_CPU0_CLK_DN<0>";
147"M_F_CPU0_SB_CB<0>";
148"M_F_CPU0_SB_CB<1>";
149"M_F_CPU0_SB_CB<2>";
150"M_F_CPU0_SB_CB<3>";
151"M_F_CPU0_SB_CB<4>";
152"M_F_CPU0_SB_CB<5>";
153"M_F_CPU0_SB_CB<6>";
154"M_F_CPU0_SA_CB<0>";
155"M_F_CPU0_SA_CB<2>";
156"M_F_CPU0_SA_CB<3>";
157"M_F_CPU0_SA_CB<5>";
158"M_F_CPU0_SA_CB<6>";
159"M_F_CPU0_SB_CA<6>";
160"M_F_CPU0_SB_CA<5>";
161"M_F_CPU0_SB_CA<4>";
162"M_F_CPU0_SA_CA<4>";
163"M_F_CPU0_SB_CA<3>";
164"M_F_CPU0_SA_CA<3>";
165"M_F_CPU0_SB_CA<2>";
166"M_F_CPU0_SA_CA<2>";
167"M_F_CPU0_SB_CA<1>";
168"M_F_CPU0_SA_CA<1>";
169"M_F_CPU0_SB_CA<0>";
170"M_F_CPU0_SA_CA<0>";
171"M_F_CPU0_ALERT_N";
172"M_F_CPU0_SB_CB<7>";
173"M_F_CPU0_SA_CB<1>";
174"M_F_CPU0_SA_CB<4>";
175"M_F_CPU0_SA_CB<7>";
176"PWRGD_CHAF_CPU0";
177"PD_CHF_CPU0_DIMM_SAA";
178"GND\g";
%"GND"
"1","(-2225,2175)","0","mstr_symbols","I150";
;
SIZE"1B"
CDS_LIB"mstr_symbols"
BODY_TYPE"PLUMBING"
VOLTAGE"0.0"
HDL_POWER"GND";
"A\NAC"23;
%"GND"
"1","(-425,1950)","0","mstr_symbols","I152";
;
CDS_LIB"mstr_symbols"
SIZE"1B"
BODY_TYPE"PLUMBING"
VOLTAGE"0.0"
HDL_POWER"GND";
"A\NAC"21;
%"VCC_CORE"
"1","(-8550,3775)","0","mstr_symbols","I175";
;
HDL_POWER"P3V3_STBY"
CDS_LIB"mstr_symbols"
VOLTAGE"3.3"
ROOM"PVCCINFAON_CPU0_CTRL";
"A"18;
%"TAP"
"1","(-7775,3525)","2","mstr_standard","I177";
;
CDS_LIB"mstr_standard"
BODY_TYPE"PLUMBING"
HDL_TAP"TRUE";
"B \NAC \NWC"4;
"S \NAC"
BN"0"147;
%"TAP"
"1","(-7775,3575)","2","mstr_standard","I178";
;
CDS_LIB"mstr_standard"
BODY_TYPE"PLUMBING"
HDL_TAP"TRUE";
"B \NAC \NWC"4;
"S \NAC"
BN"1"148;
%"TAP"
"1","(-7775,3625)","2","mstr_standard","I179";
;
CDS_LIB"mstr_standard"
BODY_TYPE"PLUMBING"
HDL_TAP"TRUE";
"B \NAC \NWC"4;
"S \NAC"
BN"2"149;
%"TAP"
"1","(-7775,3725)","2","mstr_standard","I192";
;
CDS_LIB"mstr_standard"
BODY_TYPE"PLUMBING"
HDL_TAP"TRUE";
"B \NAC \NWC"4;
"S \NAC"
BN"4"151;
%"TAP"
"1","(-7775,3675)","2","mstr_standard","I193";
;
CDS_LIB"mstr_standard"
BODY_TYPE"PLUMBING"
HDL_TAP"TRUE";
"B \NAC \NWC"4;
"S \NAC"
BN"3"150;
%"TAP"
"1","(-7775,3775)","2","mstr_standard","I194";
;
CDS_LIB"mstr_standard"
BODY_TYPE"PLUMBING"
HDL_TAP"TRUE";
"B \NAC \NWC"4;
"S \NAC"
BN"5"152;
%"TAP"
"1","(-7775,3825)","2","mstr_standard","I195";
;
CDS_LIB"mstr_standard"
BODY_TYPE"PLUMBING"
HDL_TAP"TRUE";
"B \NAC \NWC"4;
"S \NAC"
BN"6"153;
%"TAP"
"1","(-7775,3875)","2","mstr_standard","I196";
;
CDS_LIB"mstr_standard"
BODY_TYPE"PLUMBING"
HDL_TAP"TRUE";
"B \NAC \NWC"4;
"S \NAC"
BN"7"172;
%"TAP"
"1","(-7775,3975)","2","mstr_standard","I197";
;
CDS_LIB"mstr_standard"
BODY_TYPE"PLUMBING"
HDL_TAP"TRUE";
"B \NAC \NWC"1;
"S \NAC"
BN"0"154;
%"TAP"
"1","(-7775,4025)","2","mstr_standard","I198";
;
CDS_LIB"mstr_standard"
BODY_TYPE"PLUMBING"
HDL_TAP"TRUE";
"B \NAC \NWC"1;
"S \NAC"
BN"1"173;
%"TAP"
"1","(-7775,4075)","2","mstr_standard","I199";
;
CDS_LIB"mstr_standard"
BODY_TYPE"PLUMBING"
HDL_TAP"TRUE";
"B \NAC \NWC"1;
"S \NAC"
BN"2"155;
%"TAP"
"1","(-7775,4125)","2","mstr_standard","I200";
;
CDS_LIB"mstr_standard"
BODY_TYPE"PLUMBING"
HDL_TAP"TRUE";
"B \NAC \NWC"1;
"S \NAC"
BN"3"156;
%"TAP"
"1","(-7775,4225)","2","mstr_standard","I201";
;
CDS_LIB"mstr_standard"
BODY_TYPE"PLUMBING"
HDL_TAP"TRUE";
"B \NAC \NWC"1;
"S \NAC"
BN"5"157;
%"TAP"
"1","(-7775,4175)","2","mstr_standard","I202";
;
CDS_LIB"mstr_standard"
BODY_TYPE"PLUMBING"
HDL_TAP"TRUE";
"B \NAC \NWC"1;
"S \NAC"
BN"4"174;
%"TAP"
"1","(-7775,4325)","2","mstr_standard","I203";
;
CDS_LIB"mstr_standard"
BODY_TYPE"PLUMBING"
HDL_TAP"TRUE";
"B \NAC \NWC"1;
"S \NAC"
BN"7"175;
%"TAP"
"1","(-7775,4275)","2","mstr_standard","I204";
;
CDS_LIB"mstr_standard"
BODY_TYPE"PLUMBING"
HDL_TAP"TRUE";
"B \NAC \NWC"1;
"S \NAC"
BN"6"158;
%"TAP"
"1","(-7775,5025)","2","mstr_standard","I205";
;
CDS_LIB"mstr_standard"
BODY_TYPE"PLUMBING"
HDL_TAP"TRUE";
"B \NAC \NWC"3;
"S \NAC"
BN"0"169;
%"TAP"
"1","(-7775,5125)","2","mstr_standard","I206";
;
CDS_LIB"mstr_standard"
BODY_TYPE"PLUMBING"
HDL_TAP"TRUE";
"B \NAC \NWC"3;
"S \NAC"
BN"2"165;
%"TAP"
"1","(-7775,5075)","2","mstr_standard","I207";
;
CDS_LIB"mstr_standard"
BODY_TYPE"PLUMBING"
HDL_TAP"TRUE";
"B \NAC \NWC"3;
"S \NAC"
BN"1"167;
%"TAP"
"1","(-7775,5225)","2","mstr_standard","I208";
;
CDS_LIB"mstr_standard"
BODY_TYPE"PLUMBING"
HDL_TAP"TRUE";
"B \NAC \NWC"3;
"S \NAC"
BN"4"161;
%"TAP"
"1","(-7775,5175)","2","mstr_standard","I209";
;
CDS_LIB"mstr_standard"
BODY_TYPE"PLUMBING"
HDL_TAP"TRUE";
"B \NAC \NWC"3;
"S \NAC"
BN"3"163;
%"TAP"
"1","(-7775,5275)","2","mstr_standard","I210";
;
CDS_LIB"mstr_standard"
BODY_TYPE"PLUMBING"
HDL_TAP"TRUE";
"B \NAC \NWC"3;
"S \NAC"
BN"5"160;
%"TAP"
"1","(-7775,5325)","2","mstr_standard","I211";
;
CDS_LIB"mstr_standard"
BODY_TYPE"PLUMBING"
HDL_TAP"TRUE";
"B \NAC \NWC"3;
"S \NAC"
BN"6"159;
%"TAP"
"1","(-7775,5425)","2","mstr_standard","I212";
;
CDS_LIB"mstr_standard"
BODY_TYPE"PLUMBING"
HDL_TAP"TRUE";
"B \NAC \NWC"2;
"S \NAC"
BN"0"170;
%"TAP"
"1","(-7775,5475)","2","mstr_standard","I213";
;
CDS_LIB"mstr_standard"
BODY_TYPE"PLUMBING"
HDL_TAP"TRUE";
"B \NAC \NWC"2;
"S \NAC"
BN"1"168;
%"TAP"
"1","(-7775,5525)","2","mstr_standard","I214";
;
CDS_LIB"mstr_standard"
BODY_TYPE"PLUMBING"
HDL_TAP"TRUE";
"B \NAC \NWC"2;
"S \NAC"
BN"2"166;
%"TAP"
"1","(-7775,5625)","2","mstr_standard","I215";
;
CDS_LIB"mstr_standard"
BODY_TYPE"PLUMBING"
HDL_TAP"TRUE";
"B \NAC \NWC"2;
"S \NAC"
BN"4"162;
%"TAP"
"1","(-7775,5575)","2","mstr_standard","I216";
;
CDS_LIB"mstr_standard"
BODY_TYPE"PLUMBING"
HDL_TAP"TRUE";
"B \NAC \NWC"2;
"S \NAC"
BN"3"164;
%"TAP"
"1","(-7775,5675)","2","mstr_standard","I217";
;
CDS_LIB"mstr_standard"
BODY_TYPE"PLUMBING"
HDL_TAP"TRUE";
"B \NAC \NWC"2;
"S \NAC"
BN"5"68;
%"TAP"
"1","(-7775,5725)","2","mstr_standard","I218";
;
CDS_LIB"mstr_standard"
BODY_TYPE"PLUMBING"
HDL_TAP"TRUE";
"B \NAC \NWC"2;
"S \NAC"
BN"6"69;
%"TAP"
"1","(-6075,5625)","0","mstr_standard","I219";
;
CDS_LIB"mstr_standard"
BODY_TYPE"PLUMBING"
HDL_TAP"TRUE";
"B \NAC \NWC"5;
"S \NAC"
BN"29"139;
%"TAP"
"1","(-6075,5675)","0","mstr_standard","I220";
;
CDS_LIB"mstr_standard"
BODY_TYPE"PLUMBING"
HDL_TAP"TRUE";
"B \NAC \NWC"5;
"S \NAC"
BN"30"140;
%"TAP"
"1","(-6075,5575)","0","mstr_standard","I221";
;
CDS_LIB"mstr_standard"
BODY_TYPE"PLUMBING"
HDL_TAP"TRUE";
"B \NAC \NWC"5;
"S \NAC"
BN"28"70;
%"TAP"
"1","(-6075,5525)","0","mstr_standard","I222";
;
CDS_LIB"mstr_standard"
BODY_TYPE"PLUMBING"
HDL_TAP"TRUE";
"B \NAC \NWC"5;
"S \NAC"
BN"27"138;
%"TAP"
"1","(-6075,5725)","0","mstr_standard","I223";
;
CDS_LIB"mstr_standard"
BODY_TYPE"PLUMBING"
HDL_TAP"TRUE";
"B \NAC \NWC"5;
"S \NAC"
BN"31"71;
%"TAP"
"1","(-6075,5475)","0","mstr_standard","I224";
;
CDS_LIB"mstr_standard"
BODY_TYPE"PLUMBING"
HDL_TAP"TRUE";
"B \NAC \NWC"5;
"S \NAC"
BN"26"137;
%"TAP"
"1","(-6075,5425)","0","mstr_standard","I225";
;
CDS_LIB"mstr_standard"
BODY_TYPE"PLUMBING"
HDL_TAP"TRUE";
"B \NAC \NWC"5;
"S \NAC"
BN"25"136;
%"TAP"
"1","(-6075,5375)","0","mstr_standard","I226";
;
CDS_LIB"mstr_standard"
BODY_TYPE"PLUMBING"
HDL_TAP"TRUE";
"B \NAC \NWC"5;
"S \NAC"
BN"24"135;
%"TAP"
"1","(-6075,5275)","0","mstr_standard","I227";
;
CDS_LIB"mstr_standard"
BODY_TYPE"PLUMBING"
HDL_TAP"TRUE";
"B \NAC \NWC"5;
"S \NAC"
BN"22"65;
%"TAP"
"1","(-6075,5225)","0","mstr_standard","I228";
;
CDS_LIB"mstr_standard"
BODY_TYPE"PLUMBING"
HDL_TAP"TRUE";
"B \NAC \NWC"5;
"S \NAC"
BN"21"133;
%"TAP"
"1","(-6075,5325)","0","mstr_standard","I229";
;
CDS_LIB"mstr_standard"
BODY_TYPE"PLUMBING"
HDL_TAP"TRUE";
"B \NAC \NWC"5;
"S \NAC"
BN"23"134;
%"TAP"
"1","(-6075,5125)","0","mstr_standard","I230";
;
CDS_LIB"mstr_standard"
BODY_TYPE"PLUMBING"
HDL_TAP"TRUE";
"B \NAC \NWC"5;
"S \NAC"
BN"19"131;
%"TAP"
"1","(-6075,5175)","0","mstr_standard","I231";
;
CDS_LIB"mstr_standard"
BODY_TYPE"PLUMBING"
HDL_TAP"TRUE";
"B \NAC \NWC"5;
"S \NAC"
BN"20"132;
%"TAP"
"1","(-6075,4975)","0","mstr_standard","I232";
;
CDS_LIB"mstr_standard"
BODY_TYPE"PLUMBING"
HDL_TAP"TRUE";
"B \NAC \NWC"5;
"S \NAC"
BN"16"128;
%"TAP"
"1","(-6075,5075)","0","mstr_standard","I233";
;
CDS_LIB"mstr_standard"
BODY_TYPE"PLUMBING"
HDL_TAP"TRUE";
"B \NAC \NWC"5;
"S \NAC"
BN"18"130;
%"TAP"
"1","(-6075,5025)","0","mstr_standard","I234";
;
CDS_LIB"mstr_standard"
BODY_TYPE"PLUMBING"
HDL_TAP"TRUE";
"B \NAC \NWC"5;
"S \NAC"
BN"17"129;
%"TAP"
"1","(-6075,4725)","0","mstr_standard","I235";
;
CDS_LIB"mstr_standard"
BODY_TYPE"PLUMBING"
HDL_TAP"TRUE";
"B \NAC \NWC"5;
"S \NAC"
BN"11"124;
%"TAP"
"1","(-6075,4775)","0","mstr_standard","I236";
;
CDS_LIB"mstr_standard"
BODY_TYPE"PLUMBING"
HDL_TAP"TRUE";
"B \NAC \NWC"5;
"S \NAC"
BN"12"125;
%"TAP"
"1","(-6075,4825)","0","mstr_standard","I237";
;
CDS_LIB"mstr_standard"
BODY_TYPE"PLUMBING"
HDL_TAP"TRUE";
"B \NAC \NWC"5;
"S \NAC"
BN"13"126;
%"TAP"
"1","(-6075,4925)","0","mstr_standard","I238";
;
CDS_LIB"mstr_standard"
BODY_TYPE"PLUMBING"
HDL_TAP"TRUE";
"B \NAC \NWC"5;
"S \NAC"
BN"15"127;
%"TAP"
"1","(-6075,4875)","0","mstr_standard","I239";
;
CDS_LIB"mstr_standard"
BODY_TYPE"PLUMBING"
HDL_TAP"TRUE";
"B \NAC \NWC"5;
"S \NAC"
BN"14"24;
%"TAP"
"1","(-6075,4675)","0","mstr_standard","I240";
;
CDS_LIB"mstr_standard"
BODY_TYPE"PLUMBING"
HDL_TAP"TRUE";
"B \NAC \NWC"5;
"S \NAC"
BN"10"123;
%"TAP"
"1","(-6075,4625)","0","mstr_standard","I241";
;
CDS_LIB"mstr_standard"
BODY_TYPE"PLUMBING"
HDL_TAP"TRUE";
"B \NAC \NWC"5;
"S \NAC"
BN"9"122;
%"TAP"
"1","(-6075,4575)","0","mstr_standard","I242";
;
CDS_LIB"mstr_standard"
BODY_TYPE"PLUMBING"
HDL_TAP"TRUE";
"B \NAC \NWC"5;
"S \NAC"
BN"8"121;
%"TAP"
"1","(-6075,4475)","0","mstr_standard","I243";
;
CDS_LIB"mstr_standard"
BODY_TYPE"PLUMBING"
HDL_TAP"TRUE";
"B \NAC \NWC"5;
"S \NAC"
BN"6"119;
%"TAP"
"1","(-6075,4525)","0","mstr_standard","I244";
;
CDS_LIB"mstr_standard"
BODY_TYPE"PLUMBING"
HDL_TAP"TRUE";
"B \NAC \NWC"5;
"S \NAC"
BN"7"120;
%"TAP"
"1","(-6075,4425)","0","mstr_standard","I245";
;
CDS_LIB"mstr_standard"
BODY_TYPE"PLUMBING"
HDL_TAP"TRUE";
"B \NAC \NWC"5;
"S \NAC"
BN"5"118;
%"TAP"
"1","(-6075,4375)","0","mstr_standard","I246";
;
CDS_LIB"mstr_standard"
BODY_TYPE"PLUMBING"
HDL_TAP"TRUE";
"B \NAC \NWC"5;
"S \NAC"
BN"4"117;
%"TAP"
"1","(-6075,4325)","0","mstr_standard","I247";
;
CDS_LIB"mstr_standard"
BODY_TYPE"PLUMBING"
HDL_TAP"TRUE";
"B \NAC \NWC"5;
"S \NAC"
BN"3"116;
%"TAP"
"1","(-6075,4225)","0","mstr_standard","I248";
;
CDS_LIB"mstr_standard"
BODY_TYPE"PLUMBING"
HDL_TAP"TRUE";
"B \NAC \NWC"5;
"S \NAC"
BN"1"114;
%"TAP"
"1","(-6075,4275)","0","mstr_standard","I249";
;
CDS_LIB"mstr_standard"
BODY_TYPE"PLUMBING"
HDL_TAP"TRUE";
"B \NAC \NWC"5;
"S \NAC"
BN"2"115;
%"TAP"
"1","(-6075,3975)","0","mstr_standard","I250";
;
CDS_LIB"mstr_standard"
BODY_TYPE"PLUMBING"
HDL_TAP"TRUE";
"B \NAC \NWC"6;
"S \NAC"
BN"29"110;
%"TAP"
"1","(-6075,4075)","0","mstr_standard","I251";
;
CDS_LIB"mstr_standard"
BODY_TYPE"PLUMBING"
HDL_TAP"TRUE";
"B \NAC \NWC"6;
"S \NAC"
BN"31"112;
%"TAP"
"1","(-6075,4025)","0","mstr_standard","I252";
;
CDS_LIB"mstr_standard"
BODY_TYPE"PLUMBING"
HDL_TAP"TRUE";
"B \NAC \NWC"6;
"S \NAC"
BN"30"111;
%"TAP"
"1","(-6075,4175)","0","mstr_standard","I253";
;
CDS_LIB"mstr_standard"
BODY_TYPE"PLUMBING"
HDL_TAP"TRUE";
"B \NAC \NWC"5;
"S \NAC"
BN"0"113;
%"TAP"
"1","(-6075,3725)","0","mstr_standard","I254";
;
CDS_LIB"mstr_standard"
BODY_TYPE"PLUMBING"
HDL_TAP"TRUE";
"B \NAC \NWC"6;
"S \NAC"
BN"24"105;
%"TAP"
"1","(-6075,3925)","0","mstr_standard","I255";
;
CDS_LIB"mstr_standard"
BODY_TYPE"PLUMBING"
HDL_TAP"TRUE";
"B \NAC \NWC"6;
"S \NAC"
BN"28"109;
%"TAP"
"1","(-6075,3775)","0","mstr_standard","I256";
;
CDS_LIB"mstr_standard"
BODY_TYPE"PLUMBING"
HDL_TAP"TRUE";
"B \NAC \NWC"6;
"S \NAC"
BN"25"106;
%"TAP"
"1","(-6075,3875)","0","mstr_standard","I257";
;
CDS_LIB"mstr_standard"
BODY_TYPE"PLUMBING"
HDL_TAP"TRUE";
"B \NAC \NWC"6;
"S \NAC"
BN"27"108;
%"TAP"
"1","(-6075,3825)","0","mstr_standard","I258";
;
CDS_LIB"mstr_standard"
BODY_TYPE"PLUMBING"
HDL_TAP"TRUE";
"B \NAC \NWC"6;
"S \NAC"
BN"26"107;
%"TAP"
"1","(-6075,3475)","0","mstr_standard","I259";
;
CDS_LIB"mstr_standard"
BODY_TYPE"PLUMBING"
HDL_TAP"TRUE";
"B \NAC \NWC"6;
"S \NAC"
BN"19"100;
%"TAP"
"1","(-6075,3675)","0","mstr_standard","I260";
;
CDS_LIB"mstr_standard"
BODY_TYPE"PLUMBING"
HDL_TAP"TRUE";
"B \NAC \NWC"6;
"S \NAC"
BN"23"104;
%"TAP"
"1","(-6075,3525)","0","mstr_standard","I261";
;
CDS_LIB"mstr_standard"
BODY_TYPE"PLUMBING"
HDL_TAP"TRUE";
"B \NAC \NWC"6;
"S \NAC"
BN"20"101;
%"TAP"
"1","(-6075,3625)","0","mstr_standard","I262";
;
CDS_LIB"mstr_standard"
BODY_TYPE"PLUMBING"
HDL_TAP"TRUE";
"B \NAC \NWC"6;
"S \NAC"
BN"22"103;
%"TAP"
"1","(-6075,3575)","0","mstr_standard","I263";
;
CDS_LIB"mstr_standard"
BODY_TYPE"PLUMBING"
HDL_TAP"TRUE";
"B \NAC \NWC"6;
"S \NAC"
BN"21"102;
%"TAP"
"1","(-6075,3325)","0","mstr_standard","I264";
;
CDS_LIB"mstr_standard"
BODY_TYPE"PLUMBING"
HDL_TAP"TRUE";
"B \NAC \NWC"6;
"S \NAC"
BN"16"97;
%"TAP"
"1","(-6075,3375)","0","mstr_standard","I265";
;
CDS_LIB"mstr_standard"
BODY_TYPE"PLUMBING"
HDL_TAP"TRUE";
"B \NAC \NWC"6;
"S \NAC"
BN"17"98;
%"TAP"
"1","(-6075,3425)","0","mstr_standard","I266";
;
CDS_LIB"mstr_standard"
BODY_TYPE"PLUMBING"
HDL_TAP"TRUE";
"B \NAC \NWC"6;
"S \NAC"
BN"18"99;
%"TAP"
"1","(-6075,3225)","0","mstr_standard","I267";
;
CDS_LIB"mstr_standard"
BODY_TYPE"PLUMBING"
HDL_TAP"TRUE";
"B \NAC \NWC"6;
"S \NAC"
BN"14"95;
%"TAP"
"1","(-6075,3275)","0","mstr_standard","I268";
;
CDS_LIB"mstr_standard"
BODY_TYPE"PLUMBING"
HDL_TAP"TRUE";
"B \NAC \NWC"6;
"S \NAC"
BN"15"96;
%"TAP"
"1","(-6075,3175)","0","mstr_standard","I269";
;
CDS_LIB"mstr_standard"
BODY_TYPE"PLUMBING"
HDL_TAP"TRUE";
"B \NAC \NWC"6;
"S \NAC"
BN"13"94;
%"TAP"
"1","(-6075,3125)","0","mstr_standard","I270";
;
CDS_LIB"mstr_standard"
BODY_TYPE"PLUMBING"
HDL_TAP"TRUE";
"B \NAC \NWC"6;
"S \NAC"
BN"12"93;
%"TAP"
"1","(-6075,3075)","0","mstr_standard","I271";
;
CDS_LIB"mstr_standard"
BODY_TYPE"PLUMBING"
HDL_TAP"TRUE";
"B \NAC \NWC"6;
"S \NAC"
BN"11"92;
%"TAP"
"1","(-6075,3025)","0","mstr_standard","I272";
;
CDS_LIB"mstr_standard"
BODY_TYPE"PLUMBING"
HDL_TAP"TRUE";
"B \NAC \NWC"6;
"S \NAC"
BN"10"91;
%"TAP"
"1","(-6075,2975)","0","mstr_standard","I273";
;
CDS_LIB"mstr_standard"
BODY_TYPE"PLUMBING"
HDL_TAP"TRUE";
"B \NAC \NWC"6;
"S \NAC"
BN"9"90;
%"TAP"
"1","(-6075,2925)","0","mstr_standard","I274";
;
CDS_LIB"mstr_standard"
BODY_TYPE"PLUMBING"
HDL_TAP"TRUE";
"B \NAC \NWC"6;
"S \NAC"
BN"8"89;
%"TAP"
"1","(-6075,2825)","0","mstr_standard","I275";
;
CDS_LIB"mstr_standard"
BODY_TYPE"PLUMBING"
HDL_TAP"TRUE";
"B \NAC \NWC"6;
"S \NAC"
BN"6"87;
%"TAP"
"1","(-6075,2875)","0","mstr_standard","I276";
;
CDS_LIB"mstr_standard"
BODY_TYPE"PLUMBING"
HDL_TAP"TRUE";
"B \NAC \NWC"6;
"S \NAC"
BN"7"88;
%"TAP"
"1","(-6075,2775)","0","mstr_standard","I277";
;
CDS_LIB"mstr_standard"
BODY_TYPE"PLUMBING"
HDL_TAP"TRUE";
"B \NAC \NWC"6;
"S \NAC"
BN"5"86;
%"TAP"
"1","(-6075,2725)","0","mstr_standard","I278";
;
CDS_LIB"mstr_standard"
BODY_TYPE"PLUMBING"
HDL_TAP"TRUE";
"B \NAC \NWC"6;
"S \NAC"
BN"4"85;
%"TAP"
"1","(-6075,2675)","0","mstr_standard","I279";
;
CDS_LIB"mstr_standard"
BODY_TYPE"PLUMBING"
HDL_TAP"TRUE";
"B \NAC \NWC"6;
"S \NAC"
BN"3"84;
%"TAP"
"1","(-6075,2625)","0","mstr_standard","I280";
;
CDS_LIB"mstr_standard"
BODY_TYPE"PLUMBING"
HDL_TAP"TRUE";
"B \NAC \NWC"6;
"S \NAC"
BN"2"83;
%"TAP"
"1","(-6075,2525)","0","mstr_standard","I281";
;
CDS_LIB"mstr_standard"
BODY_TYPE"PLUMBING"
HDL_TAP"TRUE";
"B \NAC \NWC"6;
"S \NAC"
BN"0"81;
%"TAP"
"1","(-6075,2575)","0","mstr_standard","I282";
;
CDS_LIB"mstr_standard"
BODY_TYPE"PLUMBING"
HDL_TAP"TRUE";
"B \NAC \NWC"6;
"S \NAC"
BN"1"82;
%"GND"
"1","(-6400,1375)","0","mstr_symbols","I332";
;
SIZE"1B"
CDS_LIB"mstr_symbols"
BOM_COST"MEM"
BODY_TYPE"PLUMBING"
VOLTAGE"0.0"
HDL_POWER"GND";
"A\NAC"11;
%"Q_RES"
"2","(-6400,1600)","0","pure_quanta","I349";
;
LOCATION"R764"
$SEC"1"
CDS_SEC"1"
WATTAGE"1/16W"
MATERIAL"CHIP"
TOLERANCE"1%"
VALUE"84.5K"
PART_NUMBER"CS38452FB05"
PACK_TYPE"0402LF"
CDS_LIB"pure_quanta";
"A"
$PN"1"177;
"B"
$PN"2"11;
%"SCONN288_DDR506112002KQ"
"1","(-6925,3975)","0","pure_quanta","I350";
;
LOCATION"J23"
$SEC"1"
CDS_SEC"1"
VALUE"SCONN288_DDR506112002KQ"
PART_TYPE"SMLF"
MATERIAL"IO"
PART_NUMBER"DFHST8FS479"
CDS_LMAN_SYM_OUTLINE"-450,1900,450,-1850"
NEEDS_NO_SIZE"TRUE"
CDS_LIB"pure_quanta";
"PWR_GOOD||FAIL_N"
$PN"147"16;
"DQ31_A"
$PN"194"71;
"CB7_A"
$PN"205"175;
"CB4_A"
$PN"58"174;
"CB1_A"
$PN"53"173;
"CB7_B"
$PN"236"172;
"ALERT_N \B"
$PN"62"171;
"CA0_A"
$PN"66"170;
"CA0_B"
$PN"76"169;
"CA1_A"
$PN"211"168;
"CA1_B"
$PN"221"167;
"CA2_A"
$PN"68"166;
"CA2_B"
$PN"78"165;
"CA3_A"
$PN"213"164;
"CA3_B"
$PN"223"163;
"CA4_A"
$PN"70"162;
"CA4_B"
$PN"80"161;
"CA5_A"
$PN"215"68;
"CA5_B"
$PN"225"160;
"CA6_A"
$PN"72"69;
"CA6_B"
$PN"82"159;
"CB6_A"
$PN"203"158;
"CB5_A"
$PN"60"157;
"CB3_A"
$PN"198"156;
"CB2_A"
$PN"196"155;
"CB0_A"
$PN"51"154;
"CB6_B"
$PN"234"153;
"CB5_B"
$PN"91"152;
"CB4_B"
$PN"89"151;
"CB3_B"
$PN"243"150;
"CB2_B"
$PN"241"149;
"CB1_B"
$PN"98"148;
"CB0_B"
$PN"96"147;
"CK_C \B"
$PN"218"146;
"CK_T"
$PN"217"145;
"CS0_A_N"
$PN"64"144;
"CS0_B_N"
$PN"84"143;
"CS1_A_N"
$PN"209"142;
"CS1_B_N"
$PN"229"141;
"DQ30_A"
$PN"192"140;
"DQ29_A"
$PN"49"139;
"DQ28_A"
$PN"47"70;
"DQ27_A"
$PN"187"138;
"DQ26_A"
$PN"185"137;
"DQ25_A"
$PN"42"136;
"DQ24_A"
$PN"40"135;
"DQ23_A"
$PN"183"134;
"DQ22_A"
$PN"181"65;
"DQ21_A"
$PN"38"133;
"DQ20_A"
$PN"36"132;
"DQ19_A"
$PN"176"131;
"DQ18_A"
$PN"174"130;
"DQ17_A"
$PN"31"129;
"DQ16_A"
$PN"29"128;
"DQ15_A"
$PN"172"127;
"DQ14_A"
$PN"170"24;
"DQ13_A"
$PN"27"126;
"DQ12_A"
$PN"25"125;
"DQ11_A"
$PN"165"124;
"DQ10_A"
$PN"163"123;
"DQ9_A"
$PN"20"122;
"DQ8_A"
$PN"18"121;
"DQ7_A"
$PN"161"120;
"DQ6_A"
$PN"159"119;
"DQ5_A"
$PN"16"118;
"DQ4_A"
$PN"14"117;
"DQ3_A"
$PN"154"116;
"DQ2_A"
$PN"152"115;
"DQ1_A"
$PN"9"114;
"DQ0_A"
$PN"7"113;
"DQ31_B"
$PN"287"112;
"DQ30_B"
$PN"285"111;
"DQ29_B"
$PN"142"110;
"DQ28_B"
$PN"140"109;
"DQ27_B"
$PN"280"108;
"DQ26_B"
$PN"278"107;
"DQ25_B"
$PN"135"106;
"DQ24_B"
$PN"133"105;
"DQ23_B"
$PN"276"104;
"DQ22_B"
$PN"274"103;
"DQ21_B"
$PN"131"102;
"DQ20_B"
$PN"129"101;
"DQ19_B"
$PN"269"100;
"DQ18_B"
$PN"267"99;
"DQ17_B"
$PN"124"98;
"DQ16_B"
$PN"122"97;
"DQ15_B"
$PN"265"96;
"DQ14_B"
$PN"263"95;
"DQ13_B"
$PN"120"94;
"DQ12_B"
$PN"118"93;
"DQ11_B"
$PN"258"92;
"DQ10_B"
$PN"256"91;
"DQ9_B"
$PN"113"90;
"DQ8_B"
$PN"111"89;
"DQ7_B"
$PN"254"88;
"DQ6_B"
$PN"252"87;
"DQ5_B"
$PN"109"86;
"DQ4_B"
$PN"107"85;
"DQ3_B"
$PN"247"84;
"DQ2_B"
$PN"245"83;
"DQ1_B"
$PN"102"82;
"DQ0_B"
$PN"100"81;
"HAS"
$PN"148"19;
"HSCL"
$PN"4"15;
"HSDA"
$PN"5"14;
"LBD||RSP_A_N"
$PN"86"80;
"LBS||RSP_B_N"
$PN"87"79;
"PAR_A"
$PN"74"67;
"PAR_B"
$PN"227"66;
"RESET_N \B"
$PN"207"78;
"RFU6"
$PN"232"20;
"RFU5"
$PN"231"77;
"RFU4"
$PN"220"76;
"RFU3"
$PN"150"75;
"RFU2"
$PN"149"74;
"RFU1"
$PN"144"73;
"RFU0"
$PN"2"72;
"VIN_MGMT"
$PN"3"18;
%"SCONN288_DDR506112002KQ"
"3","(-1325,3950)","0","pure_quanta","I352";
;
LOCATION"J23"
$SEC"3"
CDS_SEC"3"
VALUE"SCONN288_DDR506112002KQ"
PART_TYPE"SMLF"
MATERIAL"IO"
PART_NUMBER"DFHST8FS479"
CDS_LMAN_SYM_OUTLINE"-450,1800,450,-1750"
NEEDS_NO_SIZE"TRUE"
CDS_LIB"pure_quanta";
"G3"
$PN"G3"21;
"G2"
$PN"G2"21;
"G1"
$PN"G1"21;
"VSS62"
$PN"141"21;
"VSS61"
$PN"139"21;
"VSS60"
$PN"136"21;
"VSS58"
$PN"132"21;
"VSS104"
$PN"240"23;
"VSS102"
$PN"235"23;
"VSS100"
$PN"230"23;
"VIN_BULK2"
$PN"146"22;
"VIN_BULK1"
$PN"145"22;
"VIN_BULK0"
$PN"1"22;
"VSS126"
$PN"288"23;
"VSS125"
$PN"286"23;
"VSS124"
$PN"284"23;
"VSS123"
$PN"281"23;
"VSS122"
$PN"279"23;
"VSS121"
$PN"277"23;
"VSS120"
$PN"275"23;
"VSS119"
$PN"273"23;
"VSS118"
$PN"270"23;
"VSS117"
$PN"268"23;
"VSS116"
$PN"266"23;
"VSS115"
$PN"264"23;
"VSS114"
$PN"262"23;
"VSS113"
$PN"259"23;
"VSS112"
$PN"257"23;
"VSS111"
$PN"255"23;
"VSS110"
$PN"253"23;
"VSS109"
$PN"251"23;
"VSS108"
$PN"248"23;
"VSS107"
$PN"246"23;
"VSS106"
$PN"244"23;
"VSS105"
$PN"242"23;
"VSS103"
$PN"237"23;
"VSS101"
$PN"233"23;
"VSS99"
$PN"228"23;
"VSS98"
$PN"226"23;
"VSS97"
$PN"224"23;
"VSS96"
$PN"222"23;
"VSS95"
$PN"219"23;
"VSS94"
$PN"216"23;
"VSS93"
$PN"214"23;
"VSS92"
$PN"212"23;
"VSS91"
$PN"210"23;
"VSS90"
$PN"208"23;
"VSS89"
$PN"206"23;
"VSS88"
$PN"204"23;
"VSS87"
$PN"202"23;
"VSS86"
$PN"199"23;
"VSS85"
$PN"197"23;
"VSS84"
$PN"195"23;
"VSS83"
$PN"193"23;
"VSS82"
$PN"191"23;
"VSS81"
$PN"188"23;
"VSS80"
$PN"186"23;
"VSS79"
$PN"184"23;
"VSS78"
$PN"182"23;
"VSS77"
$PN"180"23;
"VSS76"
$PN"177"23;
"VSS75"
$PN"175"23;
"VSS74"
$PN"173"23;
"VSS73"
$PN"171"23;
"VSS72"
$PN"169"23;
"VSS71"
$PN"166"23;
"VSS70"
$PN"164"23;
"VSS69"
$PN"162"23;
"VSS68"
$PN"160"23;
"VSS67"
$PN"158"23;
"VSS66"
$PN"155"23;
"VSS65"
$PN"153"23;
"VSS64"
$PN"151"23;
"VSS63"
$PN"143"21;
"VSS59"
$PN"134"21;
"VSS57"
$PN"130"21;
"VSS56"
$PN"128"21;
"VSS55"
$PN"125"21;
"VSS54"
$PN"123"21;
"VSS53"
$PN"121"21;
"VSS52"
$PN"119"21;
"VSS51"
$PN"117"21;
"VSS50"
$PN"114"21;
"VSS49"
$PN"112"21;
"VSS48"
$PN"110"21;
"VSS47"
$PN"108"21;
"VSS46"
$PN"106"21;
"VSS45"
$PN"103"21;
"VSS44"
$PN"101"21;
"VSS43"
$PN"99"21;
"VSS42"
$PN"97"21;
"VSS41"
$PN"95"21;
"VSS40"
$PN"92"21;
"VSS39"
$PN"90"21;
"VSS38"
$PN"88"21;
"VSS37"
$PN"85"21;
"VSS36"
$PN"83"21;
"VSS35"
$PN"81"21;
"VSS34"
$PN"79"21;
"VSS33"
$PN"77"21;
"VSS32"
$PN"75"21;
"VSS31"
$PN"73"21;
"VSS30"
$PN"71"21;
"VSS29"
$PN"69"21;
"VSS28"
$PN"67"21;
"VSS27"
$PN"65"21;
"VSS26"
$PN"63"21;
"VSS25"
$PN"61"21;
"VSS24"
$PN"59"21;
"VSS23"
$PN"57"21;
"VSS22"
$PN"54"21;
"VSS21"
$PN"52"21;
"VSS20"
$PN"50"21;
"VSS19"
$PN"48"21;
"VSS18"
$PN"46"21;
"VSS17"
$PN"43"21;
"VSS16"
$PN"41"21;
"VSS15"
$PN"39"21;
"VSS14"
$PN"37"21;
"VSS13"
$PN"35"21;
"VSS12"
$PN"32"21;
"VSS11"
$PN"30"21;
"VSS10"
$PN"28"21;
"VSS9"
$PN"26"21;
"VSS8"
$PN"24"21;
"VSS7"
$PN"21"21;
"VSS6"
$PN"19"21;
"VSS5"
$PN"17"21;
"VSS4"
$PN"15"21;
"VSS3"
$PN"13"21;
"VSS2"
$PN"10"21;
"VSS1"
$PN"8"21;
"VSS0"
$PN"6"21;
%"Q_CAP"
"1","(-8650,3575)","2","pure_quanta","I361";
;
LOCATION"C108"
$SEC"1"
CDS_SEC"1"
MATERIAL"X7R"
VALUE"0.1UF"
TOLERANCE"10%"
VOLTAGE"25V"
PACK_TYPE"0402"
PART_NUMBER"CH4104K1B00"
CDS_LIB"pure_quanta"
BOM_COST"MEM"
ROOM"MEM_CH_A_CPU0_DIMM1";
"B"
$PN"2"12;
"A"
$PN"1"18;
%"GND"
"1","(-8650,3350)","0","mstr_symbols","I362";
;
CDS_LIB"mstr_symbols"
SIZE"1B"
BOM_COST"MEM"
BODY_TYPE"PLUMBING"
VOLTAGE"0"
ROOM"MEM_EFGH_DECOUPLING_CAPS"
HDL_POWER"GND";
"A\NAC"12;
%"Q_RES"
"1","(-8550,2475)","2","pure_quanta","I364";
;
LOCATION"R296"
$SEC"1"
CDS_SEC"1"
VALUE"0"
CDS_LIB"pure_quanta"
BOM_COST"MEM"
WATTAGE"1/16W"
MATERIAL"CHIP"
TOLERANCE"5%"
PART_NUMBER"CS00002JB38"
PACK_TYPE"0402LF"
ROOM"RST_CPU0_PLD_TO_DIMM";
"B"
$PN"2"176;
"A"
$PN"1"16;
%"Q_RES"
"2","(-8425,2625)","0","pure_quanta","I365";
;
LOCATION"R94"
$SEC"1"
CDS_SEC"1"
WATTAGE"1/16W"
MATERIAL"EMPTY"
TOLERANCE"5%"
VALUE"1K"
PACK_TYPE"0402LF"
CDS_LIB"pure_quanta"
BOM_COST"MEM"
PART_NUMBER"TMP_QCS21002JB34"
ROOM"MEM_CH_A_CPU0_DIMM1";
"A"
$PN"1"13;
"B"
$PN"2"16;
%"VCC_CORE"
"1","(-8425,2800)","0","mstr_symbols","I366";
;
HDL_POWER"P3V3_STBY"
CDS_LIB"mstr_symbols"
VOLTAGE"3.3"
ROOM"PVCCINFAON_CPU0_CTRL";
"A"13;
%"TAP"
"1","(-3375,4775)","0","mstr_standard","I372";
;
CDS_LIB"mstr_standard"
BODY_TYPE"PLUMBING"
HDL_TAP"TRUE";
"B \NAC \NWC"7;
"S \NAC"
BN"9"28;
%"TAP"
"1","(-3375,4675)","0","mstr_standard","I373";
;
CDS_LIB"mstr_standard"
BODY_TYPE"PLUMBING"
HDL_TAP"TRUE";
"B \NAC \NWC"7;
"S \NAC"
BN"8"30;
%"TAP"
"1","(-3375,4475)","0","mstr_standard","I374";
;
CDS_LIB"mstr_standard"
BODY_TYPE"PLUMBING"
HDL_TAP"TRUE";
"B \NAC \NWC"7;
"S \NAC"
BN"6"35;
%"TAP"
"1","(-3375,4575)","0","mstr_standard","I375";
;
CDS_LIB"mstr_standard"
BODY_TYPE"PLUMBING"
HDL_TAP"TRUE";
"B \NAC \NWC"7;
"S \NAC"
BN"7"64;
%"TAP"
"1","(-3375,4375)","0","mstr_standard","I376";
;
CDS_LIB"mstr_standard"
BODY_TYPE"PLUMBING"
HDL_TAP"TRUE";
"B \NAC \NWC"7;
"S \NAC"
BN"5"39;
%"TAP"
"1","(-3575,4725)","0","mstr_standard","I377";
;
CDS_LIB"mstr_standard"
BODY_TYPE"PLUMBING"
HDL_TAP"TRUE";
"B \NAC \NWC"8;
"S \NAC"
BN"8"29;
%"TAP"
"1","(-3575,4825)","0","mstr_standard","I378";
;
CDS_LIB"mstr_standard"
BODY_TYPE"PLUMBING"
HDL_TAP"TRUE";
"B \NAC \NWC"8;
"S \NAC"
BN"9"27;
%"TAP"
"1","(-3575,4625)","0","mstr_standard","I379";
;
CDS_LIB"mstr_standard"
BODY_TYPE"PLUMBING"
HDL_TAP"TRUE";
"B \NAC \NWC"8;
"S \NAC"
BN"7"32;
%"TAP"
"1","(-3575,4525)","0","mstr_standard","I380";
;
CDS_LIB"mstr_standard"
BODY_TYPE"PLUMBING"
HDL_TAP"TRUE";
"B \NAC \NWC"8;
"S \NAC"
BN"6"63;
%"TAP"
"1","(-3575,4425)","0","mstr_standard","I381";
;
CDS_LIB"mstr_standard"
BODY_TYPE"PLUMBING"
HDL_TAP"TRUE";
"B \NAC \NWC"8;
"S \NAC"
BN"5"38;
%"TAP"
"1","(-3375,4275)","0","mstr_standard","I382";
;
CDS_LIB"mstr_standard"
BODY_TYPE"PLUMBING"
HDL_TAP"TRUE";
"B \NAC \NWC"7;
"S \NAC"
BN"4"43;
%"TAP"
"1","(-3375,4175)","0","mstr_standard","I383";
;
CDS_LIB"mstr_standard"
BODY_TYPE"PLUMBING"
HDL_TAP"TRUE";
"B \NAC \NWC"7;
"S \NAC"
BN"3"47;
%"TAP"
"1","(-3375,4075)","0","mstr_standard","I384";
;
CDS_LIB"mstr_standard"
BODY_TYPE"PLUMBING"
HDL_TAP"TRUE";
"B \NAC \NWC"7;
"S \NAC"
BN"2"51;
%"TAP"
"1","(-3375,3975)","0","mstr_standard","I385";
;
CDS_LIB"mstr_standard"
BODY_TYPE"PLUMBING"
HDL_TAP"TRUE";
"B \NAC \NWC"7;
"S \NAC"
BN"1"55;
%"TAP"
"1","(-3375,3875)","0","mstr_standard","I386";
;
CDS_LIB"mstr_standard"
BODY_TYPE"PLUMBING"
HDL_TAP"TRUE";
"B \NAC \NWC"7;
"S \NAC"
BN"0"59;
%"TAP"
"1","(-3575,4225)","0","mstr_standard","I387";
;
CDS_LIB"mstr_standard"
BODY_TYPE"PLUMBING"
HDL_TAP"TRUE";
"B \NAC \NWC"8;
"S \NAC"
BN"3"46;
%"TAP"
"1","(-3575,4325)","0","mstr_standard","I388";
;
CDS_LIB"mstr_standard"
BODY_TYPE"PLUMBING"
HDL_TAP"TRUE";
"B \NAC \NWC"8;
"S \NAC"
BN"4"42;
%"TAP"
"1","(-3575,4125)","0","mstr_standard","I389";
;
CDS_LIB"mstr_standard"
BODY_TYPE"PLUMBING"
HDL_TAP"TRUE";
"B \NAC \NWC"8;
"S \NAC"
BN"2"50;
%"TAP"
"1","(-3575,4025)","0","mstr_standard","I390";
;
CDS_LIB"mstr_standard"
BODY_TYPE"PLUMBING"
HDL_TAP"TRUE";
"B \NAC \NWC"8;
"S \NAC"
BN"1"54;
%"TAP"
"1","(-3575,3925)","0","mstr_standard","I391";
;
CDS_LIB"mstr_standard"
BODY_TYPE"PLUMBING"
HDL_TAP"TRUE";
"B \NAC \NWC"8;
"S \NAC"
BN"0"58;
%"TAP"
"1","(-3375,3725)","0","mstr_standard","I392";
;
CDS_LIB"mstr_standard"
BODY_TYPE"PLUMBING"
HDL_TAP"TRUE";
"B \NAC \NWC"9;
"S \NAC"
BN"9"26;
%"TAP"
"1","(-3375,3625)","0","mstr_standard","I393";
;
CDS_LIB"mstr_standard"
BODY_TYPE"PLUMBING"
HDL_TAP"TRUE";
"B \NAC \NWC"9;
"S \NAC"
BN"8"61;
%"TAP"
"1","(-3375,3525)","0","mstr_standard","I394";
;
CDS_LIB"mstr_standard"
BODY_TYPE"PLUMBING"
HDL_TAP"TRUE";
"B \NAC \NWC"9;
"S \NAC"
BN"7"31;
%"TAP"
"1","(-3375,3325)","0","mstr_standard","I395";
;
CDS_LIB"mstr_standard"
BODY_TYPE"PLUMBING"
HDL_TAP"TRUE";
"B \NAC \NWC"9;
"S \NAC"
BN"5"37;
%"TAP"
"1","(-3375,3425)","0","mstr_standard","I396";
;
CDS_LIB"mstr_standard"
BODY_TYPE"PLUMBING"
HDL_TAP"TRUE";
"B \NAC \NWC"9;
"S \NAC"
BN"6"34;
%"TAP"
"1","(-3575,3675)","0","mstr_standard","I397";
;
CDS_LIB"mstr_standard"
BODY_TYPE"PLUMBING"
HDL_TAP"TRUE";
"B \NAC \NWC"10;
"S \NAC"
BN"8"62;
%"TAP"
"1","(-3575,3775)","0","mstr_standard","I398";
;
CDS_LIB"mstr_standard"
BODY_TYPE"PLUMBING"
HDL_TAP"TRUE";
"B \NAC \NWC"10;
"S \NAC"
BN"9"25;
%"TAP"
"1","(-3575,3575)","0","mstr_standard","I399";
;
CDS_LIB"mstr_standard"
BODY_TYPE"PLUMBING"
HDL_TAP"TRUE";
"B \NAC \NWC"10;
"S \NAC"
BN"7"60;
%"TAP"
"1","(-3575,3475)","0","mstr_standard","I400";
;
CDS_LIB"mstr_standard"
BODY_TYPE"PLUMBING"
HDL_TAP"TRUE";
"B \NAC \NWC"10;
"S \NAC"
BN"6"33;
%"TAP"
"1","(-3575,3375)","0","mstr_standard","I401";
;
CDS_LIB"mstr_standard"
BODY_TYPE"PLUMBING"
HDL_TAP"TRUE";
"B \NAC \NWC"10;
"S \NAC"
BN"5"36;
%"TAP"
"1","(-3375,3225)","0","mstr_standard","I402";
;
CDS_LIB"mstr_standard"
BODY_TYPE"PLUMBING"
HDL_TAP"TRUE";
"B \NAC \NWC"9;
"S \NAC"
BN"4"41;
%"TAP"
"1","(-3375,3125)","0","mstr_standard","I403";
;
CDS_LIB"mstr_standard"
BODY_TYPE"PLUMBING"
HDL_TAP"TRUE";
"B \NAC \NWC"9;
"S \NAC"
BN"3"45;
%"TAP"
"1","(-3375,3025)","0","mstr_standard","I404";
;
CDS_LIB"mstr_standard"
BODY_TYPE"PLUMBING"
HDL_TAP"TRUE";
"B \NAC \NWC"9;
"S \NAC"
BN"2"49;
%"TAP"
"1","(-3375,2825)","0","mstr_standard","I405";
;
CDS_LIB"mstr_standard"
BODY_TYPE"PLUMBING"
HDL_TAP"TRUE";
"B \NAC \NWC"9;
"S \NAC"
BN"0"57;
%"TAP"
"1","(-3375,2925)","0","mstr_standard","I406";
;
CDS_LIB"mstr_standard"
BODY_TYPE"PLUMBING"
HDL_TAP"TRUE";
"B \NAC \NWC"9;
"S \NAC"
BN"1"53;
%"TAP"
"1","(-3575,3175)","0","mstr_standard","I407";
;
CDS_LIB"mstr_standard"
BODY_TYPE"PLUMBING"
HDL_TAP"TRUE";
"B \NAC \NWC"10;
"S \NAC"
BN"3"44;
%"TAP"
"1","(-3575,3275)","0","mstr_standard","I408";
;
CDS_LIB"mstr_standard"
BODY_TYPE"PLUMBING"
HDL_TAP"TRUE";
"B \NAC \NWC"10;
"S \NAC"
BN"4"40;
%"TAP"
"1","(-3575,3075)","0","mstr_standard","I409";
;
CDS_LIB"mstr_standard"
BODY_TYPE"PLUMBING"
HDL_TAP"TRUE";
"B \NAC \NWC"10;
"S \NAC"
BN"2"48;
%"TAP"
"1","(-3575,2975)","0","mstr_standard","I410";
;
CDS_LIB"mstr_standard"
BODY_TYPE"PLUMBING"
HDL_TAP"TRUE";
"B \NAC \NWC"10;
"S \NAC"
BN"1"52;
%"TAP"
"1","(-3575,2875)","0","mstr_standard","I411";
;
CDS_LIB"mstr_standard"
BODY_TYPE"PLUMBING"
HDL_TAP"TRUE";
"B \NAC \NWC"10;
"S \NAC"
BN"0"56;
%"SCONN288_DDR506112002KQ"
"2","(-4525,3825)","0","pure_quanta","I412";
;
LOCATION"J23"
$SEC"2"
CDS_SEC"2"
PART_TYPE"SMLF"
MATERIAL"IO"
VALUE"SCONN288_DDR506112002KQ"
PART_NUMBER"DFHST8FS479"
CDS_LMAN_SYM_OUTLINE"-600,1150,600,-1150"
NEEDS_NO_SIZE"TRUE"
CDS_LIB"pure_quanta";
"DQS7_A_C||TDQS7_A_C \B"
$PN"178"64;
"DQS6_A_T||TDQS6_A_T"
$PN"168"63;
"DQS8_B_T||TDQS8_B_T"
$PN"283"62;
"DQS8_B_C||TDQS8_B_C \B"
$PN"282"61;
"DQS7_B_T||TDQS7_B_T"
$PN"272"60;
"DQS0_A_C \B"
$PN"12"59;
"DQS0_A_T"
$PN"11"58;
"DQS0_B_C \B"
$PN"105"57;
"DQS0_B_T"
$PN"104"56;
"DQS1_A_C \B"
$PN"23"55;
"DQS1_A_T"
$PN"22"54;
"DQS1_B_C \B"
$PN"116"53;
"DQS1_B_T"
$PN"115"52;
"DQS2_A_C \B"
$PN"34"51;
"DQS2_A_T"
$PN"33"50;
"DQS2_B_C \B"
$PN"127"49;
"DQS2_B_T"
$PN"126"48;
"DQS3_A_C \B"
$PN"45"47;
"DQS3_A_T"
$PN"44"46;
"DQS3_B_C \B"
$PN"138"45;
"DQS3_B_T"
$PN"137"44;
"DQS4_A_C \B"
$PN"56"43;
"DQS4_A_T"
$PN"55"42;
"DQS4_B_C \B"
$PN"238"41;
"DQS4_B_T"
$PN"239"40;
"DQS5_A_C||TDQS5_A_C||DQS5_A_T||TDQS5_A_T \B"
$PN"156"39;
"DQS5_A_T||TDQS5_A_T"
$PN"157"38;
"DQS5_B_C||TDQS5_B_C \B"
$PN"249"37;
"DQS5_B_T||TDQS5_B_T"
$PN"250"36;
"DQS6_A_C||TDQS6_A_C||DQS6_A_T||TDQS6_A_T \B"
$PN"167"35;
"DQS6_B_C||TDQS6_B_C \B"
$PN"260"34;
"DQS6_B_T||TDQS6_B_T"
$PN"261"33;
"DQS7_A_T||TDQS7_A_T"
$PN"179"32;
"DQS7_B_C||TDQS7_B_C \B"
$PN"271"31;
"DQS8_A_C||TDQS8_A_C \B"
$PN"189"30;
"DQS8_A_T||TDQS8_A_T"
$PN"190"29;
"DQS9_A_C||TDQS9_A_C \B"
$PN"200"28;
"DQS9_A_T||TDQS9_A_T"
$PN"201"27;
"DQS9_B_C||TDQS9_B_C \B"
$PN"94"26;
"DQS9_B_T||TDQS9_B_T||DBI4_B_N"
$PN"93"25;
%"GND"
"1","(-2925,5800)","0","pure_quanta_power","I413";
;
SIZE"1B"
BOM_COST"MEM"
CDS_LIB"pure_quanta_power"
ROOM"MEM_EFGH_DECOUPLING_CAPS"
HDL_POWER"GND";
"A<SIZE-1..0>\NAC"178;
%"Q_CAP"
"1","(-2925,6150)","2","pure_quanta","I414";
;
LOCATION"C154"
$SEC"1"
CDS_SEC"1"
MATERIAL"X6S"
TOLERANCE"10%"
VALUE"10UF"
PART_NUMBER"CH6104KEA00"
VOLTAGE"25V"
PACK_TYPE"C0805"
CDS_LIB"pure_quanta"
BOM_COST"MEM"
ROOM"MEM_CH_A_CPU0_DIMM1";
"B"
$PN"2"178;
"A"
$PN"1"22;
%"Q_CAP"
"1","(-2350,6150)","2","pure_quanta","I415";
;
LOCATION"C155"
$SEC"1"
CDS_SEC"1"
MATERIAL"X6S"
TOLERANCE"10%"
VALUE"10UF"
PART_NUMBER"CH6104KEA00"
VOLTAGE"25V"
PACK_TYPE"C0805"
CDS_LIB"pure_quanta"
BOM_COST"MEM"
ROOM"MEM_CH_A_CPU0_DIMM1";
"B"
$PN"2"178;
"A"
$PN"1"22;
%"UNIVERSAL_POWER"
"1","(-2925,6475)","0","pure_quanta_power","I416";
;
HDL_POWER"P12V_MEM_1"
BOM_COST"VR_SYSTEM"
CDS_LIB"pure_quanta_power";
"A"22;
%"Q_RES"
"1","(-7825,3025)","0","pure_quanta","I418";
;
$LOCATION"R1573"
CDS_LOCATION"R1573"
$SEC"1"
CDS_SEC"1"
VALUE"49.9"
MATERIAL"CHIP"
PACK_TYPE"0402LF"
WATTAGE"1/16W"
TOLERANCE"1%"
PART_NUMBER"CS04992FB07"
CDS_LIB"pure_quanta";
"B"
$PN"2"15;
"A"
$PN"1"17;
END.
